(kicad_pcb
	(version 20241229)
	(generator "pcbnew")
	(generator_version "9.0")
	(general
		(thickness 1.62)
		(legacy_teardrops no)
	)
	(paper "A4")
	(title_block
		(title "OCuLink to 10GbE adapter")
		(date "2026-02-23")
		(rev "1.1.0")
		(company "Antmicro Ltd")
		(comment 1 "www.antmicro.com")
		(comment 9 "footprints 30-35 of 510")
	)
	(layers
		(0 "F.Cu" signal)
		(4 "In1.Cu" signal)
		(6 "In2.Cu" signal)
		(8 "In3.Cu" signal)
		(10 "In4.Cu" signal)
		(12 "In5.Cu" signal)
		(14 "In6.Cu" signal)
		(2 "B.Cu" signal)
		(9 "F.Adhes" user "F.Adhesive")
		(11 "B.Adhes" user "B.Adhesive")
		(13 "F.Paste" user)
		(15 "B.Paste" user)
		(5 "F.SilkS" user "F.Silkscreen")
		(7 "B.SilkS" user "B.Silkscreen")
		(1 "F.Mask" user)
		(3 "B.Mask" user)
		(17 "Dwgs.User" user "User.Drawings")
		(19 "Cmts.User" user "User.Comments")
		(21 "Eco1.User" user "User.Eco1")
		(23 "Eco2.User" user "User.Eco2")
		(25 "Edge.Cuts" user)
		(27 "Margin" user)
		(31 "F.CrtYd" user "F.Courtyard")
		(29 "B.CrtYd" user "B.Courtyard")
		(35 "F.Fab" user)
		(33 "B.Fab" user)
	)
	(footprint "antmicro-footprints:R_0402_1005Metric"
		(layer "F.Cu")
		(at 57.15 125.1 180)
		(descr "Resistor SMD 0402")
		(tags "resistor SMD 0402")
		(property "Reference" "R145"
			(at -1.5 -0.772697 0)
			(layer "F.SilkS")
			(effects
				(font
					(size 0.7 0.7)
					(thickness 0.15)
				)
				(justify right top)
			)
		)
		(property "Value" "R_1k_0402"
			(at -1.011843 1.772046 0)
			(layer "F.Fab")
			(hide yes)
			(effects
				(font
					(size 0.7 0.7)
					(thickness 0.15)
				)
				(justify right top)
			)
		)
		(property "Datasheet" "https://www.bourns.com/docs/product-datasheets/cr.pdf"
			(at 0 0 0)
			(layer "F.Fab")
			(hide yes)
			(effects
				(font
					(size 1.27 1.27)
					(thickness 0.15)
				)
			)
		)
		(property "Description" "SMD Chip Resistor, 1 kohm, ± 1%, 63 mW, 0402 [1005 Metric], Thick Film, General Purpose"
			(at 0 0 0)
			(layer "F.Fab")
			(hide yes)
			(effects
				(font
					(size 1.27 1.27)
					(thickness 0.15)
				)
			)
		)
		(property "MPN" "CR0402-FX-1001GLF"
			(at 0 0 180)
			(unlocked yes)
			(layer "F.Fab")
			(hide yes)
			(effects
				(font
					(size 1 1)
					(thickness 0.15)
				)
			)
		)
		(property "Manufacturer" "Bourns"
			(at 0 0 180)
			(unlocked yes)
			(layer "F.Fab")
			(hide yes)
			(effects
				(font
					(size 1 1)
					(thickness 0.15)
				)
			)
		)
		(property "License" "Apache-2.0"
			(at 0 0 180)
			(unlocked yes)
			(layer "F.Fab")
			(hide yes)
			(effects
				(font
					(size 1 1)
					(thickness 0.15)
				)
			)
		)
		(property "Author" "Antmicro"
			(at 0 0 180)
			(unlocked yes)
			(layer "F.Fab")
			(hide yes)
			(effects
				(font
					(size 1 1)
					(thickness 0.15)
				)
			)
		)
		(property "Val" "1k"
			(at 0 0 180)
			(unlocked yes)
			(layer "F.Fab")
			(hide yes)
			(effects
				(font
					(size 1 1)
					(thickness 0.15)
				)
			)
		)
		(property "Tolerance" "1%"
			(at 0 0 180)
			(unlocked yes)
			(layer "F.Fab")
			(hide yes)
			(effects
				(font
					(size 1 1)
					(thickness 0.15)
				)
			)
		)
		(sheetname "/Power/")
		(sheetfile "power.kicad_sch")
		(attr smd)
		(fp_poly
			(pts
				(xy -0.925 -0.47) (xy 0.925 -0.47) (xy 0.925 0.47) (xy -0.925 0.47)
			)
			(stroke
				(width 0.05)
				(type default)
			)
			(fill no)
			(layer "F.CrtYd")
		)
		(fp_poly
			(pts
				(xy -0.5 -0.25) (xy 0.5 -0.25) (xy 0.5 0.25) (xy -0.5 0.25)
			)
			(stroke
				(width 0.15)
				(type solid)
			)
			(fill no)
			(layer "F.Fab")
		)
		(pad "1" smd roundrect
			(at -0.48 0 180)
			(size 0.59 0.64)
			(layers "F.Cu" "F.Mask" "F.Paste")
			(roundrect_rratio 0.25)
			(net 416 "Net-(Q5-C)")
			(pintype "passive")
		)
		(pad "2" smd roundrect
			(at 0.48 0 180)
			(size 0.59 0.64)
			(layers "F.Cu" "F.Mask" "F.Paste")
			(roundrect_rratio 0.25)
			(net 411 "Net-(D17-C)")
			(pintype "passive")
		)
	)
	(footprint "antmicro-footprints:R_0402_1005Metric"
		(layer "F.Cu")
		(at 72.8 91.305 90)
		(descr "Resistor SMD 0402")
		(tags "resistor SMD 0402")
		(property "Reference" "R96"
			(at 0.785 0.34 90)
			(layer "F.SilkS")
			(effects
				(font
					(size 0.7 0.7)
					(thickness 0.15)
				)
				(justify left bottom)
			)
		)
		(property "Value" "R_10k_0402"
			(at -1.011843 1.772046 90)
			(layer "F.Fab")
			(hide yes)
			(effects
				(font
					(size 0.7 0.7)
					(thickness 0.15)
				)
				(justify left bottom)
			)
		)
		(property "Datasheet" "https://www.bourns.com/docs/product-datasheets/cr.pdf"
			(at 0 0 90)
			(layer "F.Fab")
			(hide yes)
			(effects
				(font
					(size 1.27 1.27)
					(thickness 0.15)
				)
			)
		)
		(property "Description" "SMD Chip Resistor, 10 kohm, ± 1%, 62.5 mW, 0402 [1005 Metric], Thick Film, General Purpose"
			(at 0 0 90)
			(layer "F.Fab")
			(hide yes)
			(effects
				(font
					(size 1.27 1.27)
					(thickness 0.15)
				)
			)
		)
		(property "MPN" "CR0402-FX-1002GLF"
			(at 0 0 90)
			(unlocked yes)
			(layer "F.Fab")
			(hide yes)
			(effects
				(font
					(size 1 1)
					(thickness 0.15)
				)
			)
		)
		(property "Manufacturer" "Bourns"
			(at 0 0 90)
			(unlocked yes)
			(layer "F.Fab")
			(hide yes)
			(effects
				(font
					(size 1 1)
					(thickness 0.15)
				)
			)
		)
		(property "License" "Apache-2.0"
			(at 0 0 90)
			(unlocked yes)
			(layer "F.Fab")
			(hide yes)
			(effects
				(font
					(size 1 1)
					(thickness 0.15)
				)
			)
		)
		(property "Author" "Antmicro"
			(at 0 0 90)
			(unlocked yes)
			(layer "F.Fab")
			(hide yes)
			(effects
				(font
					(size 1 1)
					(thickness 0.15)
				)
			)
		)
		(property "Val" "10k"
			(at 0 0 90)
			(unlocked yes)
			(layer "F.Fab")
			(hide yes)
			(effects
				(font
					(size 1 1)
					(thickness 0.15)
				)
			)
		)
		(property "Tolerance" "1%"
			(at 0 0 90)
			(unlocked yes)
			(layer "F.Fab")
			(hide yes)
			(effects
				(font
					(size 1 1)
					(thickness 0.15)
				)
			)
		)
		(sheetname "/X710-AT2 Misc/")
		(sheetfile "x710-at2-mics.kicad_sch")
		(attr smd exclude_from_pos_files exclude_from_bom dnp)
		(fp_rect
			(start -0.925 -0.47)
			(end 0.925 0.47)
			(stroke
				(width 0.05)
				(type default)
			)
			(fill no)
			(layer "F.CrtYd")
		)
		(fp_rect
			(start -0.5 -0.25)
			(end 0.5 0.25)
			(stroke
				(width 0.15)
				(type solid)
			)
			(fill no)
			(layer "F.Fab")
		)
		(pad "1" smd roundrect
			(at -0.48 0 90)
			(size 0.59 0.64)
			(layers "F.Cu" "F.Mask" "F.Paste")
			(roundrect_rratio 0.25)
			(net 99 "/X710-AT2 Misc/LAN_PWR_GOOD")
			(pintype "passive")
		)
		(pad "2" smd roundrect
			(at 0.48 0 90)
			(size 0.59 0.64)
			(layers "F.Cu" "F.Mask" "F.Paste")
			(roundrect_rratio 0.25)
			(net 7 "+3V3")
			(pintype "passive")
		)
	)
	(footprint "antmicro-footprints:R_0402_1005Metric"
		(layer "F.Cu")
		(at 57.15 122.75 180)
		(descr "Resistor SMD 0402")
		(tags "resistor SMD 0402")
		(property "Reference" "R146"
			(at -1.5 -0.772697 0)
			(layer "F.SilkS")
			(effects
				(font
					(size 0.7 0.7)
					(thickness 0.15)
				)
				(justify right top)
			)
		)
		(property "Value" "R_1k_0402"
			(at -1.011843 1.772046 0)
			(layer "F.Fab")
			(hide yes)
			(effects
				(font
					(size 0.7 0.7)
					(thickness 0.15)
				)
				(justify right top)
			)
		)
		(property "Datasheet" "https://www.bourns.com/docs/product-datasheets/cr.pdf"
			(at 0 0 0)
			(layer "F.Fab")
			(hide yes)
			(effects
				(font
					(size 1.27 1.27)
					(thickness 0.15)
				)
			)
		)
		(property "Description" "SMD Chip Resistor, 1 kohm, ± 1%, 63 mW, 0402 [1005 Metric], Thick Film, General Purpose"
			(at 0 0 0)
			(layer "F.Fab")
			(hide yes)
			(effects
				(font
					(size 1.27 1.27)
					(thickness 0.15)
				)
			)
		)
		(property "MPN" "CR0402-FX-1001GLF"
			(at 0 0 180)
			(unlocked yes)
			(layer "F.Fab")
			(hide yes)
			(effects
				(font
					(size 1 1)
					(thickness 0.15)
				)
			)
		)
		(property "Manufacturer" "Bourns"
			(at 0 0 180)
			(unlocked yes)
			(layer "F.Fab")
			(hide yes)
			(effects
				(font
					(size 1 1)
					(thickness 0.15)
				)
			)
		)
		(property "License" "Apache-2.0"
			(at 0 0 180)
			(unlocked yes)
			(layer "F.Fab")
			(hide yes)
			(effects
				(font
					(size 1 1)
					(thickness 0.15)
				)
			)
		)
		(property "Author" "Antmicro"
			(at 0 0 180)
			(unlocked yes)
			(layer "F.Fab")
			(hide yes)
			(effects
				(font
					(size 1 1)
					(thickness 0.15)
				)
			)
		)
		(property "Val" "1k"
			(at 0 0 180)
			(unlocked yes)
			(layer "F.Fab")
			(hide yes)
			(effects
				(font
					(size 1 1)
					(thickness 0.15)
				)
			)
		)
		(property "Tolerance" "1%"
			(at 0 0 180)
			(unlocked yes)
			(layer "F.Fab")
			(hide yes)
			(effects
				(font
					(size 1 1)
					(thickness 0.15)
				)
			)
		)
		(sheetname "/Power/")
		(sheetfile "power.kicad_sch")
		(attr smd)
		(fp_poly
			(pts
				(xy -0.925 -0.47) (xy 0.925 -0.47) (xy 0.925 0.47) (xy -0.925 0.47)
			)
			(stroke
				(width 0.05)
				(type default)
			)
			(fill no)
			(layer "F.CrtYd")
		)
		(fp_poly
			(pts
				(xy -0.5 -0.25) (xy 0.5 -0.25) (xy 0.5 0.25) (xy -0.5 0.25)
			)
			(stroke
				(width 0.15)
				(type solid)
			)
			(fill no)
			(layer "F.Fab")
		)
		(pad "1" smd roundrect
			(at -0.48 0 180)
			(size 0.59 0.64)
			(layers "F.Cu" "F.Mask" "F.Paste")
			(roundrect_rratio 0.25)
			(net 417 "Net-(Q7-C)")
			(pintype "passive")
		)
		(pad "2" smd roundrect
			(at 0.48 0 180)
			(size 0.59 0.64)
			(layers "F.Cu" "F.Mask" "F.Paste")
			(roundrect_rratio 0.25)
			(net 412 "Net-(D18-C)")
			(pintype "passive")
		)
	)
	(footprint "antmicro-footprints:R_0402_1005Metric"
		(layer "F.Cu")
		(at 82.25 83.15 180)
		(descr "Resistor SMD 0402")
		(tags "resistor SMD 0402")
		(property "Reference" "R173"
			(at -0.8 -0.45 0)
			(layer "F.SilkS")
			(effects
				(font
					(size 0.7 0.7)
					(thickness 0.15)
				)
				(justify left bottom)
			)
		)
		(property "Value" "R_0R_0402"
			(at -1.011843 1.772046 0)
			(layer "F.Fab")
			(hide yes)
			(effects
				(font
					(size 0.7 0.7)
					(thickness 0.15)
				)
				(justify right top)
			)
		)
		(property "Datasheet" "https://industrial.panasonic.com/cdbs/www-data/pdf/RDA0000/AOA0000C301.pdf"
			(at 0 0 0)
			(layer "F.Fab")
			(hide yes)
			(effects
				(font
					(size 1.27 1.27)
					(thickness 0.15)
				)
			)
		)
		(property "Description" "SMD Chip Resistor, Jumper, 0 ohm, 100 mW, 0402 [1005 Metric], Thick Film, General Purpose"
			(at 0 0 0)
			(layer "F.Fab")
			(hide yes)
			(effects
				(font
					(size 1.27 1.27)
					(thickness 0.15)
				)
			)
		)
		(property "MPN" "ERJ2GE0R00X"
			(at 0 0 180)
			(unlocked yes)
			(layer "F.Fab")
			(hide yes)
			(effects
				(font
					(size 1 1)
					(thickness 0.15)
				)
			)
		)
		(property "Manufacturer" "Panasonic"
			(at 0 0 180)
			(unlocked yes)
			(layer "F.Fab")
			(hide yes)
			(effects
				(font
					(size 1 1)
					(thickness 0.15)
				)
			)
		)
		(property "License" "Apache-2.0"
			(at 0 0 180)
			(unlocked yes)
			(layer "F.Fab")
			(hide yes)
			(effects
				(font
					(size 1 1)
					(thickness 0.15)
				)
			)
		)
		(property "Author" "Antmicro"
			(at 0 0 180)
			(unlocked yes)
			(layer "F.Fab")
			(hide yes)
			(effects
				(font
					(size 1 1)
					(thickness 0.15)
				)
			)
		)
		(property "Val" "0R"
			(at 0 0 180)
			(unlocked yes)
			(layer "F.Fab")
			(hide yes)
			(effects
				(font
					(size 1 1)
					(thickness 0.15)
				)
			)
		)
		(property "Tolerance" "~"
			(at 0 0 180)
			(unlocked yes)
			(layer "F.Fab")
			(hide yes)
			(effects
				(font
					(size 1 1)
					(thickness 0.15)
				)
			)
		)
		(property "Current" "1A"
			(at 0 0 180)
			(unlocked yes)
			(layer "F.Fab")
			(hide yes)
			(effects
				(font
					(size 1 1)
					(thickness 0.15)
				)
			)
		)
		(sheetname "/X710-AT2 Misc/")
		(sheetfile "x710-at2-mics.kicad_sch")
		(attr smd)
		(fp_rect
			(start -0.925 -0.47)
			(end 0.925 0.47)
			(stroke
				(width 0.05)
				(type default)
			)
			(fill no)
			(layer "F.CrtYd")
		)
		(fp_rect
			(start -0.5 -0.25)
			(end 0.5 0.25)
			(stroke
				(width 0.15)
				(type solid)
			)
			(fill no)
			(layer "F.Fab")
		)
		(pad "1" smd roundrect
			(at -0.48 0 180)
			(size 0.59 0.64)
			(layers "F.Cu" "F.Mask" "F.Paste")
			(roundrect_rratio 0.25)
			(net 78 "Net-(U10-VCC)")
			(pintype "passive")
		)
		(pad "2" smd roundrect
			(at 0.48 0 180)
			(size 0.59 0.64)
			(layers "F.Cu" "F.Mask" "F.Paste")
			(roundrect_rratio 0.25)
			(net 7 "+3V3")
			(pintype "passive")
		)
	)
	(footprint "antmicro-footprints:C_0402_1005Metric"
		(layer "F.Cu")
		(at 96 65.285 -90)
		(descr "Capacitor SMD 0402")
		(tags "capacitor SMD 0402")
		(property "Reference" "C197"
			(at 0.842273 -0.399995 270)
			(layer "F.SilkS")
			(effects
				(font
					(size 0.7 0.7)
					(thickness 0.15)
				)
				(justify right bottom)
			)
		)
		(property "Value" "C_220n_16V_0402"
			(at -1.022927 2.155213 270)
			(layer "F.Fab")
			(hide yes)
			(effects
				(font
					(size 0.7 0.7)
					(thickness 0.15)
				)
				(justify left bottom)
			)
		)
		(property "Datasheet" "https://www.murata.com/products/productdetail?partno=GRM155R71C224KA12%23"
			(at 0 0 270)
			(layer "F.Fab")
			(hide yes)
			(effects
				(font
					(size 1.27 1.27)
					(thickness 0.15)
				)
			)
		)
		(property "Description" "SMD Multilayer Ceramic Capacitor, 0.22 µF, 16 V, 0402 [1005 Metric], ± 10%, X7R, GRM Series"
			(at 0 0 270)
			(layer "F.Fab")
			(hide yes)
			(effects
				(font
					(size 1.27 1.27)
					(thickness 0.15)
				)
			)
		)
		(property "MPN" "GRM155R71C224KA12D"
			(at 0 0 270)
			(unlocked yes)
			(layer "F.Fab")
			(hide yes)
			(effects
				(font
					(size 1 1)
					(thickness 0.15)
				)
			)
		)
		(property "Manufacturer" "Murata"
			(at 0 0 270)
			(unlocked yes)
			(layer "F.Fab")
			(hide yes)
			(effects
				(font
					(size 1 1)
					(thickness 0.15)
				)
			)
		)
		(property "License" "Apache-2.0"
			(at 0 0 270)
			(unlocked yes)
			(layer "F.Fab")
			(hide yes)
			(effects
				(font
					(size 1 1)
					(thickness 0.15)
				)
			)
		)
		(property "Author" "Antmicro"
			(at 0 0 270)
			(unlocked yes)
			(layer "F.Fab")
			(hide yes)
			(effects
				(font
					(size 1 1)
					(thickness 0.15)
				)
			)
		)
		(property "Val" "220n"
			(at 0 0 270)
			(unlocked yes)
			(layer "F.Fab")
			(hide yes)
			(effects
				(font
					(size 1 1)
					(thickness 0.15)
				)
			)
		)
		(property "Voltage" "16V"
			(at 0 0 270)
			(unlocked yes)
			(layer "F.Fab")
			(hide yes)
			(effects
				(font
					(size 1 1)
					(thickness 0.15)
				)
			)
		)
		(property "Dielectric" "X7R"
			(at 0 0 270)
			(unlocked yes)
			(layer "F.Fab")
			(hide yes)
			(effects
				(font
					(size 1 1)
					(thickness 0.15)
				)
			)
		)
		(sheetname "/X710-AT2 PCIe/")
		(sheetfile "x710-at2-pcie.kicad_sch")
		(attr smd)
		(fp_rect
			(start -0.925 -0.47)
			(end 0.925 0.47)
			(stroke
				(width 0.05)
				(type default)
			)
			(fill no)
			(layer "F.CrtYd")
		)
		(fp_line
			(start -0.494 0.248)
			(end -0.494 -0.25)
			(stroke
				(width 0.15)
				(type solid)
			)
			(layer "F.Fab")
		)
		(fp_line
			(start 0.504 0.248)
			(end -0.494 0.248)
			(stroke
				(width 0.15)
				(type solid)
			)
			(layer "F.Fab")
		)
		(fp_line
			(start -0.494 -0.25)
			(end 0.504 -0.25)
			(stroke
				(width 0.15)
				(type solid)
			)
			(layer "F.Fab")
		)
		(fp_line
			(start 0.504 -0.25)
			(end 0.504 0.248)
			(stroke
				(width 0.15)
				(type solid)
			)
			(layer "F.Fab")
		)
		(pad "1" smd roundrect
			(at -0.48 0 270)
			(size 0.59 0.64)
			(layers "F.Cu" "F.Mask" "F.Paste")
			(roundrect_rratio 0.25)
			(net 26 "/OCuLink/PCIe_{x4}.TX3-")
			(pintype "passive")
		)
		(pad "2" smd roundrect
			(at 0.48 0 270)
			(size 0.59 0.64)
			(layers "F.Cu" "F.Mask" "F.Paste")
			(roundrect_rratio 0.25)
			(net 46 "/X710-AT2 PCIe/PCIe_{x4}_AC.TX3-")
			(pintype "passive")
		)
	)
	(footprint "antmicro-footprints:C_0603_1608Metric_EIA"
		(layer "F.Cu")
		(at 53.25 96.199999 -90)
		(descr "Capacitor SMD 0603, IPC-7351 Density Level A")
		(tags "Capacitor 0603")
		(property "Reference" "C40"
			(at 1.210001 0.44 270)
			(layer "F.SilkS")
			(effects
				(font
					(size 0.7 0.7)
					(thickness 0.15)
				)
				(justify right top)
			)
		)
		(property "Value" "C_22u_16V_0603"
			(at -1.42757 1.770288 90)
			(layer "F.Fab")
			(hide yes)
			(effects
				(font
					(size 0.7 0.7)
					(thickness 0.15)
				)
				(justify right top)
			)
		)
		(property "Datasheet" "https://product.samsungsem.com/mlcc/CL10A226MO7JZN.do"
			(at 0 0 90)
			(layer "F.Fab")
			(hide yes)
			(effects
				(font
					(size 1.27 1.27)
					(thickness 0.15)
				)
			)
		)
		(property "Description" "SMD Multilayer Ceramic Capacitor"
			(at 0 0 90)
			(layer "F.Fab")
			(hide yes)
			(effects
				(font
					(size 1.27 1.27)
					(thickness 0.15)
				)
			)
		)
		(property "MPN" "CL10A226MO7JZNC"
			(at 0 0 270)
			(unlocked yes)
			(layer "F.Fab")
			(hide yes)
			(effects
				(font
					(size 1 1)
					(thickness 0.15)
				)
			)
		)
		(property "Manufacturer" "Samsung Electro-Mechanics"
			(at 0 0 270)
			(unlocked yes)
			(layer "F.Fab")
			(hide yes)
			(effects
				(font
					(size 1 1)
					(thickness 0.15)
				)
			)
		)
		(property "License" "Apache-2.0"
			(at 0 0 270)
			(unlocked yes)
			(layer "F.Fab")
			(hide yes)
			(effects
				(font
					(size 1 1)
					(thickness 0.15)
				)
			)
		)
		(property "Author" "Antmicro"
			(at 0 0 270)
			(unlocked yes)
			(layer "F.Fab")
			(hide yes)
			(effects
				(font
					(size 1 1)
					(thickness 0.15)
				)
			)
		)
		(property "Val" "22u"
			(at 0 0 270)
			(unlocked yes)
			(layer "F.Fab")
			(hide yes)
			(effects
				(font
					(size 1 1)
					(thickness 0.15)
				)
			)
		)
		(property "Voltage" "16V"
			(at 0 0 270)
			(unlocked yes)
			(layer "F.Fab")
			(hide yes)
			(effects
				(font
					(size 1 1)
					(thickness 0.15)
				)
			)
		)
		(property "Dielectric" ""
			(at 0 0 270)
			(unlocked yes)
			(layer "F.Fab")
			(hide yes)
			(effects
				(font
					(size 1 1)
					(thickness 0.15)
				)
			)
		)
		(property "Public" "False"
			(at 0 0 270)
			(unlocked yes)
			(layer "F.Fab")
			(hide yes)
			(effects
				(font
					(size 1 1)
					(thickness 0.15)
				)
			)
		)
		(sheetname "/Power/")
		(sheetfile "power.kicad_sch")
		(attr smd)
		(fp_line
			(start -0.15 0.55)
			(end 0.15 0.55)
			(stroke
				(width 0.15)
				(type solid)
			)
			(layer "F.SilkS")
		)
		(fp_line
			(start -0.15 -0.55)
			(end 0.15 -0.55)
			(stroke
				(width 0.15)
				(type solid)
			)
			(layer "F.SilkS")
		)
		(fp_rect
			(start -1.25 -0.65)
			(end 1.25 0.65)
			(stroke
				(width 0.05)
				(type solid)
			)
			(fill no)
			(layer "F.CrtYd")
		)
		(fp_rect
			(start -0.8 -0.45)
			(end 0.8 0.45)
			(stroke
				(width 0.15)
				(type solid)
			)
			(fill no)
			(layer "F.Fab")
		)
		(pad "1" smd roundrect
			(at -0.7 0 270)
			(size 0.8 1.1)
			(layers "F.Cu" "F.Mask" "F.Paste")
			(roundrect_rratio 0.2)
			(net 28 "GND")
			(pintype "passive")
		)
		(pad "2" smd roundrect
			(at 0.7 0 270)
			(size 0.8 1.1)
			(layers "F.Cu" "F.Mask" "F.Paste")
			(roundrect_rratio 0.2)
			(net 314 "VCC")
			(pintype "passive")
		)
	)
)
